# S9S_MB_2U (Grand Teton) — schematic netlist excerpt (pin names and nets, part order shuffled) for the footprints in the layout excerpt that follows; sources: Cadence DE-HDL packaged netlist, KiCad conversion of 03242023_DA0F0TMBIJ0_F0T_Motherboard_J_brd_V01_OCP.brd

U38  9QXL2001BNHGI8  IC  pkg GQFN80_TH_0-5_6X6  page 206
  DIF17  = CLK_100M_OCP_V3_2_D_R_DP
  \dif16#\  = CLK_100M_OCP_V3_2_C_R_DN
  DIF16  = CLK_100M_OCP_V3_2_C_R_DP
  \dif15#\  = CLK_100M_OCP_V3_2_B_R_DN
  DIF15  = CLK_100M_OCP_V3_2_B_R_DP
  \dif14#\  = CLK_100M_OCP_V3_2_A_R_DN
  DIF14  = CLK_100M_OCP_V3_2_A_R_DP
  \dif13#\  = TP_CLK_100M_DIF13_DN
  DIF13  = TP_CLK_100M_DIF13_DP
  \dif12#\  = CLK_100M_OCP_SFF_3_R_DN
  DIF12  = CLK_100M_OCP_SFF_3_R_DP
  \dif11#\  = CLK_100M_OCP_SFF_2_R_DN
  \dif17#\  = CLK_100M_OCP_V3_2_D_R_DN
  \vddo3.3_b2\  = P3V3_DB2000_VDD
  NC1  = NC_CLK_100M_DB2000_NC1
  \^vsadr0_tri\  = PD_DB2000_SMB_SA0
  NC2  = NC_CLK_100M_DB2000_NC2
  \vdda3.3\  = P3V3_DB2000_VDDA
  NC3  = NC_CLK_100M_DB2000_NC3
  \^vsadr1_tri\  = PD_DB2000_SMB_SA1
  NC4  = NC_CLK_100M_DB2000_NC4
  \voe12#\  = FM_DB2000_12_OE_N
  \vddo3.3_b11\  = P3V3_DB2000_VDD
  DIF11  = CLK_100M_OCP_SFF_2_R_DP
  DIF18  = TP_CLK_100M_DIF18_DP
  NC5  = NC_CLK_100M_DB2000_NC5
  \voe11#\  = FM_DB2000_11_OE_N
  \dif10#\  = CLK_100M_OCP_SFF_1_R_DN
  \dif18#\  = TP_CLK_100M_DIF18_DN
  NC6  = NC_CLK_100M_DB2000_NC6
  NC7  = NC_CLK_100M_DB2000_NC7
  DIF10  = CLK_100M_OCP_SFF_1_R_DP
  DIF19  = TP_CLK_100M_DIF19_DP
  VSBEN  = FM_DB2000_VSBEN
  \voe10#||shft_ld#\  = FM_DB2000_10_OE_N
  \voe9#\  = FM_DB2000_9_OE_N
  \dif19#\  = TP_CLK_100M_DIF19_DN
  NC8  = NC_CLK_100M_DB2000_NC8
  NC9  = NC_CLK_100M_DB2000_NC9
  \dif9#\  = CLK_100M_OCP_SFF_0_R_DN
  DIF_IN  = CLK_100M_DB2000_DP
  NC10  = NC_CLK_100M_DB2000_NC10
  NC11  = NC_CLK_100M_DB2000_NC11
  DIF9  = CLK_100M_OCP_SFF_0_R_DP
  \dif_in#\  = CLK_100M_DB2000_DN
  \vddr3.3\  = P3V3_DB2000_VDDR
  \voe8#\  = FM_DB2000_8_OE_N
  \dif8#\  = CLK_100M_GPU_SWB_REF_DN
  DIF0  = CLK_100M_DB2000_CPU0_BCLK0_DP
  NC12  = NC_CLK_100M_DB2000_NC12
  NC13  = NC_CLK_100M_DB2000_NC13
  DIF8  = CLK_100M_GPU_SWB_REF_DP
  \dif0#\  = CLK_100M_DB2000_CPU0_BCLK0_DN
  NC14  = NC_CLK_100M_DB2000_NC14
  \voe7#\  = FM_DB2000_1_OE_N
  \dif7#\  = CLK_100M_DB2000_CPU1_BCLK3_DN
  DIF1  = CLK_100M_DB2000_CPU0_BCLK1_DP
  \vddo3.3_l2\  = P3V3_DB2000_VDD
  NC17  = NC_CLK_100M_DB2000_NC17
  SMBDAT  = SMB_HOST_DB2000_3V3AUX_SDA
  SMBCLK  = SMB_HOST_DB2000_3V3AUX_SCL
  NC15  = NC_CLK_100M_DB2000_NC15
  NC16  = NC_CLK_100M_DB2000_NC16
  \voe5#||data\  = FM_DB2000_1_OE_N
  NC18  = NC_CLK_100M_DB2000_NC18
  \voe6#||clk\  = FM_DB2000_1_OE_N
  \vddo3.3_l11\  = P3V3_DB2000_VDD
  DIF7  = CLK_100M_DB2000_CPU1_BCLK3_DP
  \dif1#\  = CLK_100M_DB2000_CPU0_BCLK1_DN
  DIF2  = CLK_100M_DB2000_CPU0_BCLK2_DP
  \dif2#\  = CLK_100M_DB2000_CPU0_BCLK2_DN
  DIF3  = CLK_100M_DB2000_CPU0_BCLK3_DP
  \dif3#\  = CLK_100M_DB2000_CPU0_BCLK3_DN
  \vckpwrgd_pd#\  = FM_DB2000_DEV_EN
  DIF4  = CLK_100M_DB2000_CPU1_BCLK0_DP
  \dif4#\  = CLK_100M_DB2000_CPU1_BCLK0_DN
  DIF5  = CLK_100M_DB2000_CPU1_BCLK1_DP
  \dif5#\  = CLK_100M_DB2000_CPU1_BCLK1_DN
  DIF6  = CLK_100M_DB2000_CPU1_BCLK2_DP
  \dif6#\  = CLK_100M_DB2000_CPU1_BCLK2_DN
  EPAD  = GND

(kicad_pcb
	(version 20260206)
	(generator "pcbnew")
	(generator_version "10.0")
	(general
		(thickness 1.6)
		(legacy_teardrops no)
	)
	(paper "A4")
	(title_block
		(title "03242023_DA0F0TMBIJ0_F0T_Motherboard_J_brd_V01_OCP.brd")
		(comment 1 "Grand Teton / footprint 4091 of 6105 (U38), pads 43-81 of 81")
	)
	(layers
		(0 "F.Cu" signal "TOP")
		(4 "In1.Cu" signal "GND")
		(6 "In2.Cu" signal "IN1")
		(8 "In3.Cu" signal "GND1")
		(10 "In4.Cu" signal "IN2")
		(12 "In5.Cu" signal "GND2")
		(14 "In6.Cu" signal "IN3")
		(16 "In7.Cu" signal "GND3")
		(18 "In8.Cu" signal "VCC")
		(20 "In9.Cu" signal "VCC1")
		(22 "In10.Cu" signal "GND4")
		(24 "In11.Cu" signal "IN4")
		(26 "In12.Cu" signal "GND5")
		(28 "In13.Cu" signal "IN5")
		(30 "In14.Cu" signal "GND6")
		(32 "In15.Cu" signal "IN6")
		(34 "In16.Cu" signal "GND7")
		(2 "B.Cu" signal "BOTTOM")
		(9 "F.Adhes" user "F.Adhesive")
		(11 "B.Adhes" user "B.Adhesive")
		(13 "F.Paste" user "Package Geometry/Pastemask Top")
		(15 "B.Paste" user "Package Geometry/Pastemask Bottom")
		(5 "F.SilkS" user "Ref Des/Silkscreen Top")
		(7 "B.SilkS" user "Ref Des/Silkscreen Bottom")
		(1 "F.Mask" user "Board Geometry/Soldermask Top")
		(3 "B.Mask" user "Board Geometry/Soldermask Bottom")
		(17 "Dwgs.User" user "User.Drawings")
		(19 "Cmts.User" user "User.Comments")
		(21 "Eco1.User" user "User.Eco1")
		(23 "Eco2.User" user "User.Eco2")
		(25 "Edge.Cuts" user "Board Geometry/Outline")
		(27 "Margin" user)
		(31 "F.CrtYd" user "Package Geometry/Place Bound Top")
		(29 "B.CrtYd" user "Package Geometry/Place Bound Bottom")
		(35 "F.Fab" user "Ref Des/Assembly Top")
		(33 "B.Fab" user "Ref Des/Assembly Bottom")
	)
	(footprint ""
		(layer "F.Cu")
		(at 234.998006 -126.767844 180)
		(property "Reference" "U38"
			(at -6.147308 -6.293104 0)
			(unlocked yes)
			(layer "F.SilkS")
			(effects
				(font
					(size 0.7874 0.5842)
					(thickness 0.1524)
				)
				(justify left)
			)
		)
		(property "Value" ""
			(at 0 0 180)
			(layer "F.Fab")
			(effects
				(font
					(size 1.27 1.27)
				)
			)
		)
		(duplicate_pad_numbers_are_jumpers no)
		(pad "G11" smd circle
			(at 2.249932 0.249936 180)
			(size 0.2286 0.2286)
			(layers "F.Cu" "F.Mask" "F.Paste")
			(net "NC_CLK_100M_DB2000_NC11")
		)
		(pad "G12" smd circle
			(at 2.750058 0.249936 180)
			(size 0.2286 0.2286)
			(layers "F.Cu" "F.Mask" "F.Paste")
			(net "CLK_100M_OCP_SFF_0_R_DP")
		)
		(pad "H1" smd circle
			(at -2.750058 0.750062 180)
			(size 0.2286 0.2286)
			(layers "F.Cu" "F.Mask" "F.Paste")
			(net "CLK_100M_DB2000_DN")
		)
		(pad "H2" smd circle
			(at -2.249932 0.750062 180)
			(size 0.2286 0.2286)
			(layers "F.Cu" "F.Mask" "F.Paste")
			(net "P3V3_DB2000_VDDR")
		)
		(pad "H11" smd circle
			(at 2.249932 0.750062 180)
			(size 0.2286 0.2286)
			(layers "F.Cu" "F.Mask" "F.Paste")
			(net "FM_DB2000_8_OE_N")
		)
		(pad "H12" smd circle
			(at 2.750058 0.750062 180)
			(size 0.2286 0.2286)
			(layers "F.Cu" "F.Mask" "F.Paste")
			(net "CLK_100M_GPU_SWB_REF_DN")
		)
		(pad "J1" smd circle
			(at -2.750058 1.249934 180)
			(size 0.2286 0.2286)
			(layers "F.Cu" "F.Mask" "F.Paste")
			(net "CLK_100M_DB2000_CPU0_BCLK0_DP")
		)
		(pad "J2" smd circle
			(at -2.249932 1.249934 180)
			(size 0.2286 0.2286)
			(layers "F.Cu" "F.Mask" "F.Paste")
			(net "NC_CLK_100M_DB2000_NC12")
		)
		(pad "J11" smd circle
			(at 2.249932 1.249934 180)
			(size 0.2286 0.2286)
			(layers "F.Cu" "F.Mask" "F.Paste")
			(net "NC_CLK_100M_DB2000_NC13")
		)
		(pad "J12" smd circle
			(at 2.750058 1.249934 180)
			(size 0.2286 0.2286)
			(layers "F.Cu" "F.Mask" "F.Paste")
			(net "CLK_100M_GPU_SWB_REF_DP")
		)
		(pad "K1" smd circle
			(at -2.750058 1.75006 180)
			(size 0.2286 0.2286)
			(layers "F.Cu" "F.Mask" "F.Paste")
			(net "CLK_100M_DB2000_CPU0_BCLK0_DN")
		)
		(pad "K2" smd circle
			(at -2.249932 1.75006 180)
			(size 0.2286 0.2286)
			(layers "F.Cu" "F.Mask" "F.Paste")
			(net "NC_CLK_100M_DB2000_NC14")
		)
		(pad "K11" smd circle
			(at 2.249932 1.75006 180)
			(size 0.2286 0.2286)
			(layers "F.Cu" "F.Mask" "F.Paste")
			(net "FM_DB2000_1_OE_N")
		)
		(pad "K12" smd circle
			(at 2.750058 1.75006 180)
			(size 0.2286 0.2286)
			(layers "F.Cu" "F.Mask" "F.Paste")
			(net "CLK_100M_DB2000_CPU1_BCLK3_DN")
		)
		(pad "L1" smd circle
			(at -2.750058 2.249932 180)
			(size 0.2286 0.2286)
			(layers "F.Cu" "F.Mask" "F.Paste")
			(net "CLK_100M_DB2000_CPU0_BCLK1_DP")
		)
		(pad "L2" smd circle
			(at -2.249932 2.249932 180)
			(size 0.2286 0.2286)
			(layers "F.Cu" "F.Mask" "F.Paste")
			(net "P3V3_DB2000_VDD")
		)
		(pad "L3" smd circle
			(at -1.75006 2.249932 180)
			(size 0.2286 0.2286)
			(layers "F.Cu" "F.Mask" "F.Paste")
			(net "NC_CLK_100M_DB2000_NC17")
		)
		(pad "L4" smd circle
			(at -1.249934 2.249932 180)
			(size 0.2286 0.2286)
			(layers "F.Cu" "F.Mask" "F.Paste")
			(net "SMB_HOST_DB2000_3V3AUX_SDA")
		)
		(pad "L5" smd circle
			(at -0.750062 2.249932 180)
			(size 0.2286 0.2286)
			(layers "F.Cu" "F.Mask" "F.Paste")
			(net "SMB_HOST_DB2000_3V3AUX_SCL")
		)
		(pad "L6" smd circle
			(at -0.249936 2.249932 180)
			(size 0.2286 0.2286)
			(layers "F.Cu" "F.Mask" "F.Paste")
			(net "NC_CLK_100M_DB2000_NC15")
		)
		(pad "L7" smd circle
			(at 0.249936 2.249932 180)
			(size 0.2286 0.2286)
			(layers "F.Cu" "F.Mask" "F.Paste")
			(net "NC_CLK_100M_DB2000_NC16")
		)
		(pad "L8" smd circle
			(at 0.750062 2.249932 180)
			(size 0.2286 0.2286)
			(layers "F.Cu" "F.Mask" "F.Paste")
			(net "FM_DB2000_1_OE_N")
		)
		(pad "L9" smd circle
			(at 1.249934 2.249932 180)
			(size 0.2286 0.2286)
			(layers "F.Cu" "F.Mask" "F.Paste")
			(net "NC_CLK_100M_DB2000_NC18")
		)
		(pad "L10" smd circle
			(at 1.75006 2.249932 180)
			(size 0.2286 0.2286)
			(layers "F.Cu" "F.Mask" "F.Paste")
			(net "FM_DB2000_1_OE_N")
		)
		(pad "L11" smd circle
			(at 2.249932 2.249932 180)
			(size 0.2286 0.2286)
			(layers "F.Cu" "F.Mask" "F.Paste")
			(net "P3V3_DB2000_VDD")
		)
		(pad "L12" smd circle
			(at 2.750058 2.249932 180)
			(size 0.2286 0.2286)
			(layers "F.Cu" "F.Mask" "F.Paste")
			(net "CLK_100M_DB2000_CPU1_BCLK3_DP")
		)
		(pad "M1" smd circle
			(at -2.750058 2.750058 180)
			(size 0.2286 0.2286)
			(layers "F.Cu" "F.Mask" "F.Paste")
			(net "CLK_100M_DB2000_CPU0_BCLK1_DN")
		)
		(pad "M2" smd circle
			(at -2.249932 2.750058 180)
			(size 0.2286 0.2286)
			(layers "F.Cu" "F.Mask" "F.Paste")
			(net "CLK_100M_DB2000_CPU0_BCLK2_DP")
		)
		(pad "M3" smd circle
			(at -1.75006 2.750058 180)
			(size 0.2286 0.2286)
			(layers "F.Cu" "F.Mask" "F.Paste")
			(net "CLK_100M_DB2000_CPU0_BCLK2_DN")
		)
		(pad "M4" smd circle
			(at -1.249934 2.750058 180)
			(size 0.2286 0.2286)
			(layers "F.Cu" "F.Mask" "F.Paste")
			(net "CLK_100M_DB2000_CPU0_BCLK3_DP")
		)
		(pad "M5" smd circle
			(at -0.750062 2.750058 180)
			(size 0.2286 0.2286)
			(layers "F.Cu" "F.Mask" "F.Paste")
			(net "CLK_100M_DB2000_CPU0_BCLK3_DN")
		)
		(pad "M6" smd circle
			(at -0.249936 2.750058 180)
			(size 0.2286 0.2286)
			(layers "F.Cu" "F.Mask" "F.Paste")
			(net "FM_DB2000_DEV_EN")
		)
		(pad "M7" smd circle
			(at 0.249936 2.750058 180)
			(size 0.2286 0.2286)
			(layers "F.Cu" "F.Mask" "F.Paste")
			(net "CLK_100M_DB2000_CPU1_BCLK0_DP")
		)
		(pad "M8" smd circle
			(at 0.750062 2.750058 180)
			(size 0.2286 0.2286)
			(layers "F.Cu" "F.Mask" "F.Paste")
			(net "CLK_100M_DB2000_CPU1_BCLK0_DN")
		)
		(pad "M9" smd circle
			(at 1.249934 2.750058 180)
			(size 0.2286 0.2286)
			(layers "F.Cu" "F.Mask" "F.Paste")
			(net "CLK_100M_DB2000_CPU1_BCLK1_DP")
		)
		(pad "M10" smd circle
			(at 1.75006 2.750058 180)
			(size 0.2286 0.2286)
			(layers "F.Cu" "F.Mask" "F.Paste")
			(net "CLK_100M_DB2000_CPU1_BCLK1_DN")
		)
		(pad "M11" smd circle
			(at 2.249932 2.750058 180)
			(size 0.2286 0.2286)
			(layers "F.Cu" "F.Mask" "F.Paste")
			(net "CLK_100M_DB2000_CPU1_BCLK2_DP")
		)
		(pad "M12" smd circle
			(at 2.750058 2.750058 180)
			(size 0.2286 0.2286)
			(layers "F.Cu" "F.Mask" "F.Paste")
			(net "CLK_100M_DB2000_CPU1_BCLK2_DN")
		)
		(pad "TH" smd circle
			(at 0 0 180)
			(size 0 0)
			(layers "F.Cu" "F.Mask" "F.Paste")
			(net "GND")
		)
	)
)
